# S9S_MB_2U (Grand Teton) — schematic netlist excerpt (pin names and nets, part order shuffled) for the footprints in the layout excerpt that follows; sources: Cadence DE-HDL packaged netlist, KiCad conversion of 03242023_DA0F0TMBIJ0_F0T_Motherboard_J_brd_V01_OCP.brd

J4  SCONN288_ADR50017P087CC  SCONN288_ADR50017-P087CC IO  pkg DDR288S_1-1VXB  page 85
  VIN_BULK0  = P12V_S3_AUX_CPU0_NVDIMM
  RFU0  = TP_CHB_CPU0_DIMM2_FRU_0
  VIN_MGMT  = P3V3_AUX
  HSCL  = I3C_SPD_DDRABCD_CPU0_LVC1_SCL_3
  HSDA  = I3C_SPD_DDRABCD_CPU0_LVC1_SDA
  VSS0  = GND
  DQ0_A  = M_B_CPU0_SA_DQ<0>
  VSS1  = GND
  DQ1_A  = M_B_CPU0_SA_DQ<1>
  VSS2  = GND
  DQS0_A_T  = M_B_CPU0_SA_DQS_DP<0>
  DQS0_A_C  = M_B_CPU0_SA_DQS_DN<0>
  VSS3  = GND
  DQ4_A  = M_B_CPU0_SA_DQ<4>
  VSS4  = GND
  DQ5_A  = M_B_CPU0_SA_DQ<5>
  VSS5  = GND
  DQ8_A  = M_B_CPU0_SA_DQ<8>
  VSS6  = GND
  DQ9_A  = M_B_CPU0_SA_DQ<9>
  VSS7  = GND
  DQS1_A_T  = M_B_CPU0_SA_DQS_DP<1>
  DQS1_A_C  = M_B_CPU0_SA_DQS_DN<1>
  VSS8  = GND
  DQ12_A  = M_B_CPU0_SA_DQ<12>
  VSS9  = GND
  DQ13_A  = M_B_CPU0_SA_DQ<13>
  VSS10  = GND
  DQ16_A  = M_B_CPU0_SA_DQ<16>
  VSS11  = GND
  DQ17_A  = M_B_CPU0_SA_DQ<17>
  VSS12  = GND
  DQS2_A_T  = M_B_CPU0_SA_DQS_DP<2>
  DQS2_A_C  = M_B_CPU0_SA_DQS_DN<2>
  VSS13  = GND
  DQ20_A  = M_B_CPU0_SA_DQ<20>
  VSS14  = GND
  DQ21_A  = M_B_CPU0_SA_DQ<21>
  VSS15  = GND
  DQ24_A  = M_B_CPU0_SA_DQ<24>
  VSS16  = GND
  DQ25_A  = M_B_CPU0_SA_DQ<25>
  VSS17  = GND
  DQS3_A_T  = M_B_CPU0_SA_DQS_DP<3>
  DQS3_A_C  = M_B_CPU0_SA_DQS_DN<3>
  VSS18  = GND
  DQ28_A  = M_B_CPU0_SA_DQ<28>
  VSS19  = GND
  DQ29_A  = M_B_CPU0_SA_DQ<29>
  VSS20  = GND
  CB0_A  = M_B_CPU0_SA_CB<0>
  VSS21  = GND
  CB1_A  = M_B_CPU0_SA_CB<1>
  VSS22  = GND
  DQS4_A_T  = M_B_CPU0_SA_DQS_DP<4>
  DQS4_A_C  = M_B_CPU0_SA_DQS_DN<4>
  VSS23  = GND
  CB4_A  = M_B_CPU0_SA_CB<4>
  VSS24  = GND
  CB5_A  = M_B_CPU0_SA_CB<5>
  VSS25  = GND
  ALERT_N  = M_B_CPU0_ALERT_N
  VSS26  = GND
  CS0_A_N  = M_B_CPU0_SA_CS_N<2>
  VSS27  = GND
  CA0_A  = M_B_CPU0_SA_CA<0>
  VSS28  = GND
  CA2_A  = M_B_CPU0_SA_CA<2>
  VSS29  = GND
  CA4_A  = M_B_CPU0_SA_CA<4>
  VSS30  = GND
  CA6_A  = M_B_CPU0_SA_CA<6>
  VSS31  = GND
  PAR_A  = M_B_CPU0_SA_PAR
  VSS32  = GND
  CA0_B  = M_B_CPU0_SB_CA<0>
  VSS33  = GND
  CA2_B  = M_B_CPU0_SB_CA<2>
  VSS34  = GND
  CA4_B  = M_B_CPU0_SB_CA<4>
  VSS35  = GND
  CA6_B  = M_B_CPU0_SB_CA<6>
  VSS36  = GND
  CS0_B_N  = M_B_CPU0_SB_CS_N<2>
  VSS37  = GND
  \lbd||rsp_a_n\  = M_B_CPU0_SA_RSP<1>
  \lbs||rsp_b_n\  = M_B_CPU0_SB_RSP<1>
  VSS38  = GND
  CB4_B  = M_B_CPU0_SB_CB<4>
  VSS39  = GND
  CB5_B  = M_B_CPU0_SB_CB<5>
  VSS40  = GND
  \dqs9_b_t||tdqs9_b_t||dbi4_b_n\  = M_B_CPU0_SB_DQS_DP<9>
  \dqs9_b_c||tdqs9_b_c\  = M_B_CPU0_SB_DQS_DN<9>
  VSS41  = GND
  CB0_B  = M_B_CPU0_SB_CB<0>
  VSS42  = GND
  CB1_B  = M_B_CPU0_SB_CB<1>
  VSS43  = GND
  DQ0_B  = M_B_CPU0_SB_DQ<0>
  VSS44  = GND
  DQ1_B  = M_B_CPU0_SB_DQ<1>
  VSS45  = GND
  DQS0_B_T  = M_B_CPU0_SB_DQS_DP<0>
  DQS0_B_C  = M_B_CPU0_SB_DQS_DN<0>
  VSS46  = GND
  DQ4_B  = M_B_CPU0_SB_DQ<4>
  VSS47  = GND
  DQ5_B  = M_B_CPU0_SB_DQ<5>
  VSS48  = GND
  DQ8_B  = M_B_CPU0_SB_DQ<8>
  VSS49  = GND
  DQ9_B  = M_B_CPU0_SB_DQ<9>
  VSS50  = GND
  DQS1_B_T  = M_B_CPU0_SB_DQS_DP<1>
  DQS1_B_C  = M_B_CPU0_SB_DQS_DN<1>
  VSS51  = GND
  DQ12_B  = M_B_CPU0_SB_DQ<12>
  VSS52  = GND
  DQ13_B  = M_B_CPU0_SB_DQ<13>
  VSS53  = GND
  DQ16_B  = M_B_CPU0_SB_DQ<16>
  VSS54  = GND
  DQ17_B  = M_B_CPU0_SB_DQ<17>
  VSS55  = GND
  DQS2_B_T  = M_B_CPU0_SB_DQS_DP<2>
  DQS2_B_C  = M_B_CPU0_SB_DQS_DN<2>
  VSS56  = GND
  DQ20_B  = M_B_CPU0_SB_DQ<20>
  VSS57  = GND
  DQ21_B  = M_B_CPU0_SB_DQ<21>
  VSS58  = GND
  DQ24_B  = M_B_CPU0_SB_DQ<24>
  VSS59  = GND
  DQ25_B  = M_B_CPU0_SB_DQ<25>
  VSS60  = GND
  DQS3_B_T  = M_B_CPU0_SB_DQS_DP<3>
  DQS3_B_C  = M_B_CPU0_SB_DQS_DN<3>
  VSS61  = GND
  DQ28_B  = M_B_CPU0_SB_DQ<28>
  VSS62  = GND
  DQ29_B  = M_B_CPU0_SB_DQ<29>
  VSS63  = GND
  RFU1  = TP_CHB_CPU0_DIMM2_FRU_1
  VIN_BULK1  = P12V_S3_AUX_CPU0_NVDIMM
  VIN_BULK2  = P12V_S3_AUX_CPU0_NVDIMM
  \pwr_good||fail_n\  = PWRGD_CHB_CPU0_DIMM2
  HSA  = PD_CHB_CPU0_DIMM2_SAA
  RFU2  = TP_CHB_CPU0_DIMM2_FRU_2
  RFU3  = TP_CHB_CPU0_DIMM2_FRU_3
  VSS64  = GND
  DQ2_A  = M_B_CPU0_SA_DQ<2>
  VSS65  = GND
  DQ3_A  = M_B_CPU0_SA_DQ<3>
  VSS66  = GND
  \dqs5_a_c||tdqs5_a_c||dqs5_a_t||tdqs5_a_t\  = M_B_CPU0_SA_DQS_DN<5>
  \dqs5_a_t||tdqs5_a_t\  = M_B_CPU0_SA_DQS_DP<5>
  VSS67  = GND
  DQ6_A  = M_B_CPU0_SA_DQ<6>
  VSS68  = GND
  DQ7_A  = M_B_CPU0_SA_DQ<7>
  VSS69  = GND
  DQ10_A  = M_B_CPU0_SA_DQ<10>
  VSS70  = GND
  DQ11_A  = M_B_CPU0_SA_DQ<11>
  VSS71  = GND
  \dqs6_a_c||tdqs6_a_c||dqs6_a_t||tdqs6_a_t\  = M_B_CPU0_SA_DQS_DN<6>
  \dqs6_a_t||tdqs6_a_t\  = M_B_CPU0_SA_DQS_DP<6>
  VSS72  = GND
  DQ14_A  = M_B_CPU0_SA_DQ<14>
  VSS73  = GND
  DQ15_A  = M_B_CPU0_SA_DQ<15>
  VSS74  = GND
  DQ18_A  = M_B_CPU0_SA_DQ<18>
  VSS75  = GND
  DQ19_A  = M_B_CPU0_SA_DQ<19>
  VSS76  = GND
  \dqs7_a_c||tdqs7_a_c\  = M_B_CPU0_SA_DQS_DN<7>
  \dqs7_a_t||tdqs7_a_t\  = M_B_CPU0_SA_DQS_DP<7>
  VSS77  = GND
  DQ22_A  = M_B_CPU0_SA_DQ<22>
  VSS78  = GND
  DQ23_A  = M_B_CPU0_SA_DQ<23>
  VSS79  = GND
  DQ26_A  = M_B_CPU0_SA_DQ<26>
  VSS80  = GND
  DQ27_A  = M_B_CPU0_SA_DQ<27>
  VSS81  = GND
  \dqs8_a_c||tdqs8_a_c\  = M_B_CPU0_SA_DQS_DN<8>
  \dqs8_a_t||tdqs8_a_t\  = M_B_CPU0_SA_DQS_DP<8>
  VSS82  = GND
  DQ30_A  = M_B_CPU0_SA_DQ<30>
  VSS83  = GND
  DQ31_A  = M_B_CPU0_SA_DQ<31>
  VSS84  = GND
  CB2_A  = M_B_CPU0_SA_CB<2>
  VSS85  = GND
  CB3_A  = M_B_CPU0_SA_CB<3>
  VSS86  = GND
  \dqs9_a_c||tdqs9_a_c\  = M_B_CPU0_SA_DQS_DN<9>
  \dqs9_a_t||tdqs9_a_t\  = M_B_CPU0_SA_DQS_DP<9>
  VSS87  = GND
  CB6_A  = M_B_CPU0_SA_CB<6>
  VSS88  = GND
  CB7_A  = M_B_CPU0_SA_CB<7>
  VSS89  = GND
  RESET_N  = RST_M_AB_CPU0_FPGA_N
  VSS90  = GND
  CS1_A_N  = M_B_CPU0_SA_CS_N<3>
  VSS91  = GND
  CA1_A  = M_B_CPU0_SA_CA<1>
  VSS92  = GND
  CA3_A  = M_B_CPU0_SA_CA<3>
  VSS93  = GND
  CA5_A  = M_B_CPU0_SA_CA<5>
  VSS94  = GND
  CK_T  = M_B_CPU0_CLK_DP<1>
  CK_C  = M_B_CPU0_CLK_DN<1>
  VSS95  = GND
  RFU4  = TP_CHB_CPU0_DIMM2_FRU_4
  CA1_B  = M_B_CPU0_SB_CA<1>
  VSS96  = GND
  CA3_B  = M_B_CPU0_SB_CA<3>
  VSS97  = GND
  CA5_B  = M_B_CPU0_SB_CA<5>
  VSS98  = GND
  PAR_B  = M_B_CPU0_SB_PAR
  VSS99  = GND
  CS1_B_N  = M_B_CPU0_SB_CS_N<3>
  VSS100  = GND
  RFU5  = TP_CHB_CPU0_DIMM2_FRU_5
  RFU6  = TP_CHB_CPU0_DIMM2_FRU_6
  VSS101  = GND
  CB6_B  = M_B_CPU0_SB_CB<6>
  VSS102  = GND
  CB7_B  = M_B_CPU0_SB_CB<7>
  VSS103  = GND
  DQS4_B_C  = M_B_CPU0_SB_DQS_DN<4>
  DQS4_B_T  = M_B_CPU0_SB_DQS_DP<4>
  VSS104  = GND
  CB2_B  = M_B_CPU0_SB_CB<2>
  VSS105  = GND
  CB3_B  = M_B_CPU0_SB_CB<3>
  VSS106  = GND
  DQ2_B  = M_B_CPU0_SB_DQ<2>
  VSS107  = GND
  DQ3_B  = M_B_CPU0_SB_DQ<3>
  VSS108  = GND
  \dqs5_b_c||tdqs5_b_c\  = M_B_CPU0_SB_DQS_DN<5>
  \dqs5_b_t||tdqs5_b_t\  = M_B_CPU0_SB_DQS_DP<5>
  VSS109  = GND
  DQ6_B  = M_B_CPU0_SB_DQ<6>
  VSS110  = GND
  DQ7_B  = M_B_CPU0_SB_DQ<7>
  VSS111  = GND
  DQ10_B  = M_B_CPU0_SB_DQ<10>
  VSS112  = GND
  DQ11_B  = M_B_CPU0_SB_DQ<11>
  VSS113  = GND
  \dqs6_b_c||tdqs6_b_c\  = M_B_CPU0_SB_DQS_DN<6>
  \dqs6_b_t||tdqs6_b_t\  = M_B_CPU0_SB_DQS_DP<6>
  VSS114  = GND
  DQ14_B  = M_B_CPU0_SB_DQ<14>
  VSS115  = GND
  DQ15_B  = M_B_CPU0_SB_DQ<15>
  VSS116  = GND
  DQ18_B  = M_B_CPU0_SB_DQ<18>
  VSS117  = GND
  DQ19_B  = M_B_CPU0_SB_DQ<19>
  VSS118  = GND
  \dqs7_b_c||tdqs7_b_c\  = M_B_CPU0_SB_DQS_DN<7>
  \dqs7_b_t||tdqs7_b_t\  = M_B_CPU0_SB_DQS_DP<7>
  VSS119  = GND
  DQ22_B  = M_B_CPU0_SB_DQ<22>
  VSS120  = GND
  DQ23_B  = M_B_CPU0_SB_DQ<23>
  VSS121  = GND
  DQ26_B  = M_B_CPU0_SB_DQ<26>
  VSS122  = GND
  DQ27_B  = M_B_CPU0_SB_DQ<27>
  VSS123  = GND
  \dqs8_b_c||tdqs8_b_c\  = M_B_CPU0_SB_DQS_DN<8>
  \dqs8_b_t||tdqs8_b_t\  = M_B_CPU0_SB_DQS_DP<8>
  VSS124  = GND
  DQ30_B  = M_B_CPU0_SB_DQ<30>
  VSS125  = GND
  DQ31_B  = M_B_CPU0_SB_DQ<31>
  VSS126  = GND
  G1  = GND
  G2  = GND
  G3  = GND

(kicad_pcb
	(version 20260206)
	(generator "pcbnew")
	(generator_version "10.0")
	(general
		(thickness 1.6)
		(legacy_teardrops no)
	)
	(paper "A4")
	(title_block
		(title "03242023_DA0F0TMBIJ0_F0T_Motherboard_J_brd_V01_OCP.brd")
		(comment 1 "Grand Teton / footprint 1229 of 6105 (J4), pads 92-137 of 291")
	)
	(layers
		(0 "F.Cu" signal "TOP")
		(4 "In1.Cu" signal "GND")
		(6 "In2.Cu" signal "IN1")
		(8 "In3.Cu" signal "GND1")
		(10 "In4.Cu" signal "IN2")
		(12 "In5.Cu" signal "GND2")
		(14 "In6.Cu" signal "IN3")
		(16 "In7.Cu" signal "GND3")
		(18 "In8.Cu" signal "VCC")
		(20 "In9.Cu" signal "VCC1")
		(22 "In10.Cu" signal "GND4")
		(24 "In11.Cu" signal "IN4")
		(26 "In12.Cu" signal "GND5")
		(28 "In13.Cu" signal "IN5")
		(30 "In14.Cu" signal "GND6")
		(32 "In15.Cu" signal "IN6")
		(34 "In16.Cu" signal "GND7")
		(2 "B.Cu" signal "BOTTOM")
		(9 "F.Adhes" user "F.Adhesive")
		(11 "B.Adhes" user "B.Adhesive")
		(13 "F.Paste" user "Package Geometry/Pastemask Top")
		(15 "B.Paste" user "Package Geometry/Pastemask Bottom")
		(5 "F.SilkS" user "Ref Des/Silkscreen Top")
		(7 "B.SilkS" user "Ref Des/Silkscreen Bottom")
		(1 "F.Mask" user "Board Geometry/Soldermask Top")
		(3 "B.Mask" user "Board Geometry/Soldermask Bottom")
		(17 "Dwgs.User" user "User.Drawings")
		(19 "Cmts.User" user "User.Comments")
		(21 "Eco1.User" user "User.Eco1")
		(23 "Eco2.User" user "User.Eco2")
		(25 "Edge.Cuts" user "Board Geometry/Outline")
		(27 "Margin" user)
		(31 "F.CrtYd" user "Package Geometry/Place Bound Top")
		(29 "B.CrtYd" user "Package Geometry/Place Bound Bottom")
		(35 "F.Fab" user "Ref Des/Assembly Top")
		(33 "B.Fab" user "Ref Des/Assembly Bottom")
	)
	(footprint ""
		(layer "F.Cu")
		(at 295.849548 -258.091686)
		(property "Reference" "J4"
			(at -3.683 -81.702148 0)
			(unlocked yes)
			(layer "F.SilkS")
			(effects
				(font
					(size 0.7874 0.5842)
					(thickness 0.1524)
				)
				(justify left)
			)
		)
		(property "Value" ""
			(at 0 0 0)
			(layer "F.Fab")
			(effects
				(font
					(size 1.27 1.27)
				)
			)
		)
		(duplicate_pad_numbers_are_jumpers no)
		(pad "92" smd rect
			(at -2.050034 19.12493 270)
			(size 0.519938 1.4986)
			(layers "F.Cu" "F.Mask" "F.Paste")
			(net "GND")
		)
		(pad "93" smd rect
			(at -2.050034 19.975068 270)
			(size 0.519938 1.4986)
			(layers "F.Cu" "F.Mask" "F.Paste")
			(net "M_B_CPU0_SB_DQS_DP<9>")
		)
		(pad "94" smd rect
			(at -2.050034 20.824952 270)
			(size 0.519938 1.4986)
			(layers "F.Cu" "F.Mask" "F.Paste")
			(net "M_B_CPU0_SB_DQS_DN<9>")
		)
		(pad "95" smd rect
			(at -2.050034 21.67509 270)
			(size 0.519938 1.4986)
			(layers "F.Cu" "F.Mask" "F.Paste")
			(net "GND")
		)
		(pad "96" smd rect
			(at -2.050034 22.524974 270)
			(size 0.519938 1.4986)
			(layers "F.Cu" "F.Mask" "F.Paste")
			(net "M_B_CPU0_SB_CB<0>")
		)
		(pad "97" smd rect
			(at -2.050034 23.375112 270)
			(size 0.519938 1.4986)
			(layers "F.Cu" "F.Mask" "F.Paste")
			(net "GND")
		)
		(pad "98" smd rect
			(at -2.050034 24.224996 270)
			(size 0.519938 1.4986)
			(layers "F.Cu" "F.Mask" "F.Paste")
			(net "M_B_CPU0_SB_CB<1>")
		)
		(pad "99" smd rect
			(at -2.050034 25.07488 270)
			(size 0.519938 1.4986)
			(layers "F.Cu" "F.Mask" "F.Paste")
			(net "GND")
		)
		(pad "100" smd rect
			(at -2.050034 25.925018 270)
			(size 0.519938 1.4986)
			(layers "F.Cu" "F.Mask" "F.Paste")
			(net "M_B_CPU0_SB_DQ<0>")
		)
		(pad "101" smd rect
			(at -2.050034 26.774902 270)
			(size 0.519938 1.4986)
			(layers "F.Cu" "F.Mask" "F.Paste")
			(net "GND")
		)
		(pad "102" smd rect
			(at -2.050034 27.62504 270)
			(size 0.519938 1.4986)
			(layers "F.Cu" "F.Mask" "F.Paste")
			(net "M_B_CPU0_SB_DQ<1>")
		)
		(pad "103" smd rect
			(at -2.050034 28.474924 270)
			(size 0.519938 1.4986)
			(layers "F.Cu" "F.Mask" "F.Paste")
			(net "GND")
		)
		(pad "104" smd rect
			(at -2.050034 29.325062 270)
			(size 0.519938 1.4986)
			(layers "F.Cu" "F.Mask" "F.Paste")
			(net "M_B_CPU0_SB_DQS_DP<0>")
		)
		(pad "105" smd rect
			(at -2.050034 30.174946 270)
			(size 0.519938 1.4986)
			(layers "F.Cu" "F.Mask" "F.Paste")
			(net "M_B_CPU0_SB_DQS_DN<0>")
		)
		(pad "106" smd rect
			(at -2.050034 31.025084 270)
			(size 0.519938 1.4986)
			(layers "F.Cu" "F.Mask" "F.Paste")
			(net "GND")
		)
		(pad "107" smd rect
			(at -2.050034 31.874968 270)
			(size 0.519938 1.4986)
			(layers "F.Cu" "F.Mask" "F.Paste")
			(net "M_B_CPU0_SB_DQ<4>")
		)
		(pad "108" smd rect
			(at -2.050034 32.725106 270)
			(size 0.519938 1.4986)
			(layers "F.Cu" "F.Mask" "F.Paste")
			(net "GND")
		)
		(pad "109" smd rect
			(at -2.050034 33.57499 270)
			(size 0.519938 1.4986)
			(layers "F.Cu" "F.Mask" "F.Paste")
			(net "M_B_CPU0_SB_DQ<5>")
		)
		(pad "110" smd rect
			(at -2.050034 34.425128 270)
			(size 0.519938 1.4986)
			(layers "F.Cu" "F.Mask" "F.Paste")
			(net "GND")
		)
		(pad "111" smd rect
			(at -2.050034 35.275012 270)
			(size 0.519938 1.4986)
			(layers "F.Cu" "F.Mask" "F.Paste")
			(net "M_B_CPU0_SB_DQ<8>")
		)
		(pad "112" smd rect
			(at -2.050034 36.124896 270)
			(size 0.519938 1.4986)
			(layers "F.Cu" "F.Mask" "F.Paste")
			(net "GND")
		)
		(pad "113" smd rect
			(at -2.050034 36.975034 270)
			(size 0.519938 1.4986)
			(layers "F.Cu" "F.Mask" "F.Paste")
			(net "M_B_CPU0_SB_DQ<9>")
		)
		(pad "114" smd rect
			(at -2.050034 37.824918 270)
			(size 0.519938 1.4986)
			(layers "F.Cu" "F.Mask" "F.Paste")
			(net "GND")
		)
		(pad "115" smd rect
			(at -2.050034 38.675056 270)
			(size 0.519938 1.4986)
			(layers "F.Cu" "F.Mask" "F.Paste")
			(net "M_B_CPU0_SB_DQS_DP<1>")
		)
		(pad "116" smd rect
			(at -2.050034 39.52494 270)
			(size 0.519938 1.4986)
			(layers "F.Cu" "F.Mask" "F.Paste")
			(net "M_B_CPU0_SB_DQS_DN<1>")
		)
		(pad "117" smd rect
			(at -2.050034 40.375078 270)
			(size 0.519938 1.4986)
			(layers "F.Cu" "F.Mask" "F.Paste")
			(net "GND")
		)
		(pad "118" smd rect
			(at -2.050034 41.224962 270)
			(size 0.519938 1.4986)
			(layers "F.Cu" "F.Mask" "F.Paste")
			(net "M_B_CPU0_SB_DQ<12>")
		)
		(pad "119" smd rect
			(at -2.050034 42.0751 270)
			(size 0.519938 1.4986)
			(layers "F.Cu" "F.Mask" "F.Paste")
			(net "GND")
		)
		(pad "120" smd rect
			(at -2.050034 42.924984 270)
			(size 0.519938 1.4986)
			(layers "F.Cu" "F.Mask" "F.Paste")
			(net "M_B_CPU0_SB_DQ<13>")
		)
		(pad "121" smd rect
			(at -2.050034 43.775122 270)
			(size 0.519938 1.4986)
			(layers "F.Cu" "F.Mask" "F.Paste")
			(net "GND")
		)
		(pad "122" smd rect
			(at -2.050034 44.625006 270)
			(size 0.519938 1.4986)
			(layers "F.Cu" "F.Mask" "F.Paste")
			(net "M_B_CPU0_SB_DQ<16>")
		)
		(pad "123" smd rect
			(at -2.050034 45.47489 270)
			(size 0.519938 1.4986)
			(layers "F.Cu" "F.Mask" "F.Paste")
			(net "GND")
		)
		(pad "124" smd rect
			(at -2.050034 46.325028 270)
			(size 0.519938 1.4986)
			(layers "F.Cu" "F.Mask" "F.Paste")
			(net "M_B_CPU0_SB_DQ<17>")
		)
		(pad "125" smd rect
			(at -2.050034 47.174912 270)
			(size 0.519938 1.4986)
			(layers "F.Cu" "F.Mask" "F.Paste")
			(net "GND")
		)
		(pad "126" smd rect
			(at -2.050034 48.02505 270)
			(size 0.519938 1.4986)
			(layers "F.Cu" "F.Mask" "F.Paste")
			(net "M_B_CPU0_SB_DQS_DP<2>")
		)
		(pad "127" smd rect
			(at -2.050034 48.874934 270)
			(size 0.519938 1.4986)
			(layers "F.Cu" "F.Mask" "F.Paste")
			(net "M_B_CPU0_SB_DQS_DN<2>")
		)
		(pad "128" smd rect
			(at -2.050034 49.725072 270)
			(size 0.519938 1.4986)
			(layers "F.Cu" "F.Mask" "F.Paste")
			(net "GND")
		)
		(pad "129" smd rect
			(at -2.050034 50.574956 270)
			(size 0.519938 1.4986)
			(layers "F.Cu" "F.Mask" "F.Paste")
			(net "M_B_CPU0_SB_DQ<20>")
		)
		(pad "130" smd rect
			(at -2.050034 51.425094 270)
			(size 0.519938 1.4986)
			(layers "F.Cu" "F.Mask" "F.Paste")
			(net "GND")
		)
		(pad "131" smd rect
			(at -2.050034 52.274978 270)
			(size 0.519938 1.4986)
			(layers "F.Cu" "F.Mask" "F.Paste")
			(net "M_B_CPU0_SB_DQ<21>")
		)
		(pad "132" smd rect
			(at -2.050034 53.125116 270)
			(size 0.519938 1.4986)
			(layers "F.Cu" "F.Mask" "F.Paste")
			(net "GND")
		)
		(pad "133" smd rect
			(at -2.050034 53.975 270)
			(size 0.519938 1.4986)
			(layers "F.Cu" "F.Mask" "F.Paste")
			(net "M_B_CPU0_SB_DQ<24>")
		)
		(pad "134" smd rect
			(at -2.050034 54.824884 270)
			(size 0.519938 1.4986)
			(layers "F.Cu" "F.Mask" "F.Paste")
			(net "GND")
		)
		(pad "135" smd rect
			(at -2.050034 55.675022 270)
			(size 0.519938 1.4986)
			(layers "F.Cu" "F.Mask" "F.Paste")
			(net "M_B_CPU0_SB_DQ<25>")
		)
		(pad "136" smd rect
			(at -2.050034 56.524906 270)
			(size 0.519938 1.4986)
			(layers "F.Cu" "F.Mask" "F.Paste")
			(net "GND")
		)
		(pad "137" smd rect
			(at -2.050034 57.375044 270)
			(size 0.519938 1.4986)
			(layers "F.Cu" "F.Mask" "F.Paste")
			(net "M_B_CPU0_SB_DQS_DP<3>")
		)
	)
)
